# S9S_MB_2U (Grand Teton) — schematic netlist excerpt (pin names and nets, part order shuffled) for the footprints in the layout excerpt that follows; sources: Cadence DE-HDL packaged netlist, KiCad conversion of 03242023_DA0F0TMBIJ0_F0T_Motherboard_J_brd_V01_OCP.brd

R1681  Q_RES  10K 1% CHIP  pkg 0402LF  page 213 : A = P3V3_AUX ; B = PU_RST_DEDI_BUSY_PLD_N
PR1306  Q_RES  2.2 1% CHIP  pkg 0402LF  page 290 : A = PVCCFA_EHV_FIVRA_CPU1_PVCC1 ; B = PVCCFA_EHV_FIVRA_CPU1_VDD3

(kicad_pcb
	(version 20260206)
	(generator "pcbnew")
	(generator_version "10.0")
	(general
		(thickness 1.6)
		(legacy_teardrops no)
	)
	(paper "A4")
	(title_block
		(title "03242023_DA0F0TMBIJ0_F0T_Motherboard_J_brd_V01_OCP.brd")
		(comment 1 "Grand Teton / footprints 5215-5216 of 6105")
	)
	(layers
		(0 "F.Cu" signal "TOP")
		(4 "In1.Cu" signal "GND")
		(6 "In2.Cu" signal "IN1")
		(8 "In3.Cu" signal "GND1")
		(10 "In4.Cu" signal "IN2")
		(12 "In5.Cu" signal "GND2")
		(14 "In6.Cu" signal "IN3")
		(16 "In7.Cu" signal "GND3")
		(18 "In8.Cu" signal "VCC")
		(20 "In9.Cu" signal "VCC1")
		(22 "In10.Cu" signal "GND4")
		(24 "In11.Cu" signal "IN4")
		(26 "In12.Cu" signal "GND5")
		(28 "In13.Cu" signal "IN5")
		(30 "In14.Cu" signal "GND6")
		(32 "In15.Cu" signal "IN6")
		(34 "In16.Cu" signal "GND7")
		(2 "B.Cu" signal "BOTTOM")
		(9 "F.Adhes" user "F.Adhesive")
		(11 "B.Adhes" user "B.Adhesive")
		(13 "F.Paste" user "Package Geometry/Pastemask Top")
		(15 "B.Paste" user "Package Geometry/Pastemask Bottom")
		(5 "F.SilkS" user "Ref Des/Silkscreen Top")
		(7 "B.SilkS" user "Ref Des/Silkscreen Bottom")
		(1 "F.Mask" user "Board Geometry/Soldermask Top")
		(3 "B.Mask" user "Board Geometry/Soldermask Bottom")
		(17 "Dwgs.User" user "User.Drawings")
		(19 "Cmts.User" user "User.Comments")
		(21 "Eco1.User" user "User.Eco1")
		(23 "Eco2.User" user "User.Eco2")
		(25 "Edge.Cuts" user "Board Geometry/Outline")
		(27 "Margin" user)
		(31 "F.CrtYd" user "Package Geometry/Place Bound Top")
		(29 "B.CrtYd" user "Package Geometry/Place Bound Bottom")
		(35 "F.Fab" user "Ref Des/Assembly Top")
		(33 "B.Fab" user "Ref Des/Assembly Bottom")
	)
	(footprint ""
		(layer "B.Cu")
		(at 178.803554 -354.565204 -90)
		(property "Reference" "PR1306"
			(at 0 0 90)
			(layer "B.SilkS")
			(hide yes)
			(effects
				(font
					(size 1.27 1.27)
				)
				(justify mirror)
			)
		)
		(property "Value" ""
			(at 0 0 90)
			(layer "B.Fab")
			(effects
				(font
					(size 1.27 1.27)
				)
				(justify mirror)
			)
		)
		(duplicate_pad_numbers_are_jumpers no)
		(fp_line
			(start -0.7874 0.4064)
			(end 0.7874 0.4064)
			(stroke
				(width 0.1524)
				(type default)
			)
			(layer "B.SilkS")
		)
		(fp_line
			(start 0.7874 0.4064)
			(end 0.7874 -0.4064)
			(stroke
				(width 0.1524)
				(type default)
			)
			(layer "B.SilkS")
		)
		(fp_line
			(start -0.7874 -0.4064)
			(end -0.7874 0.4064)
			(stroke
				(width 0.1524)
				(type default)
			)
			(layer "B.SilkS")
		)
		(fp_line
			(start 0.7874 -0.4064)
			(end -0.7874 -0.4064)
			(stroke
				(width 0.1524)
				(type default)
			)
			(layer "B.SilkS")
		)
		(fp_line
			(start -0.67945 0.3048)
			(end -0.120396 0.3048)
			(stroke
				(width 0.1)
				(type default)
			)
			(layer "B.Fab")
		)
		(fp_line
			(start -0.120396 0.3048)
			(end -0.120396 0.2794)
			(stroke
				(width 0.1)
				(type default)
			)
			(layer "B.Fab")
		)
		(fp_line
			(start 0.12065 0.3048)
			(end 0.67945 0.3048)
			(stroke
				(width 0.1)
				(type default)
			)
			(layer "B.Fab")
		)
		(fp_line
			(start 0.67945 0.3048)
			(end 0.67945 -0.305054)
			(stroke
				(width 0.1)
				(type default)
			)
			(layer "B.Fab")
		)
		(fp_line
			(start -0.120396 0.2794)
			(end 0.12065 0.2794)
			(stroke
				(width 0.1)
				(type default)
			)
			(layer "B.Fab")
		)
		(fp_line
			(start 0.12065 0.2794)
			(end 0.12065 0.3048)
			(stroke
				(width 0.1)
				(type default)
			)
			(layer "B.Fab")
		)
		(fp_line
			(start -0.12065 -0.2794)
			(end -0.12065 -0.3048)
			(stroke
				(width 0.1)
				(type default)
			)
			(layer "B.Fab")
		)
		(fp_line
			(start 0.12065 -0.2794)
			(end -0.12065 -0.2794)
			(stroke
				(width 0.1)
				(type default)
			)
			(layer "B.Fab")
		)
		(fp_line
			(start -0.67945 -0.3048)
			(end -0.67945 0.3048)
			(stroke
				(width 0.1)
				(type default)
			)
			(layer "B.Fab")
		)
		(fp_line
			(start -0.12065 -0.3048)
			(end -0.67945 -0.3048)
			(stroke
				(width 0.1)
				(type default)
			)
			(layer "B.Fab")
		)
		(fp_line
			(start 0.12065 -0.305054)
			(end 0.12065 -0.2794)
			(stroke
				(width 0.1)
				(type default)
			)
			(layer "B.Fab")
		)
		(fp_line
			(start 0.67945 -0.305054)
			(end 0.12065 -0.305054)
			(stroke
				(width 0.1)
				(type default)
			)
			(layer "B.Fab")
		)
		(pad "1" smd circle
			(at 0.40005 0 90)
			(size 0 0)
			(layers "B.Cu" "B.Mask" "B.Paste")
			(net "PVCCFA_EHV_FIVRA_CPU1_PVCC1")
		)
		(pad "2" smd circle
			(at -0.40005 0 90)
			(size 0 0)
			(layers "B.Cu" "B.Mask" "B.Paste")
			(net "PVCCFA_EHV_FIVRA_CPU1_VDD3")
		)
	)
	(footprint ""
		(layer "B.Cu")
		(at 157.02788 -113.756948 180)
		(property "Reference" "R1681"
			(at 0 0 0)
			(layer "B.SilkS")
			(hide yes)
			(effects
				(font
					(size 1.27 1.27)
				)
				(justify mirror)
			)
		)
		(property "Value" ""
			(at 0 0 0)
			(layer "B.Fab")
			(effects
				(font
					(size 1.27 1.27)
				)
				(justify mirror)
			)
		)
		(duplicate_pad_numbers_are_jumpers no)
		(fp_line
			(start 0.7874 0.4064)
			(end 0.7874 -0.4064)
			(stroke
				(width 0.1524)
				(type default)
			)
			(layer "B.SilkS")
		)
		(fp_line
			(start 0.7874 -0.4064)
			(end -0.7874 -0.4064)
			(stroke
				(width 0.1524)
				(type default)
			)
			(layer "B.SilkS")
		)
		(fp_line
			(start -0.7874 0.4064)
			(end 0.7874 0.4064)
			(stroke
				(width 0.1524)
				(type default)
			)
			(layer "B.SilkS")
		)
		(fp_line
			(start -0.7874 -0.4064)
			(end -0.7874 0.4064)
			(stroke
				(width 0.1524)
				(type default)
			)
			(layer "B.SilkS")
		)
		(fp_line
			(start 0.67945 0.3048)
			(end 0.67945 -0.305054)
			(stroke
				(width 0.1)
				(type default)
			)
			(layer "B.Fab")
		)
		(fp_line
			(start 0.67945 -0.305054)
			(end 0.12065 -0.305054)
			(stroke
				(width 0.1)
				(type default)
			)
			(layer "B.Fab")
		)
		(fp_line
			(start 0.12065 0.3048)
			(end 0.67945 0.3048)
			(stroke
				(width 0.1)
				(type default)
			)
			(layer "B.Fab")
		)
		(fp_line
			(start 0.12065 0.2794)
			(end 0.12065 0.3048)
			(stroke
				(width 0.1)
				(type default)
			)
			(layer "B.Fab")
		)
		(fp_line
			(start 0.12065 -0.2794)
			(end -0.12065 -0.2794)
			(stroke
				(width 0.1)
				(type default)
			)
			(layer "B.Fab")
		)
		(fp_line
			(start 0.12065 -0.305054)
			(end 0.12065 -0.2794)
			(stroke
				(width 0.1)
				(type default)
			)
			(layer "B.Fab")
		)
		(fp_line
			(start -0.120396 0.3048)
			(end -0.120396 0.2794)
			(stroke
				(width 0.1)
				(type default)
			)
			(layer "B.Fab")
		)
		(fp_line
			(start -0.120396 0.2794)
			(end 0.12065 0.2794)
			(stroke
				(width 0.1)
				(type default)
			)
			(layer "B.Fab")
		)
		(fp_line
			(start -0.12065 -0.2794)
			(end -0.12065 -0.3048)
			(stroke
				(width 0.1)
				(type default)
			)
			(layer "B.Fab")
		)
		(fp_line
			(start -0.12065 -0.3048)
			(end -0.67945 -0.3048)
			(stroke
				(width 0.1)
				(type default)
			)
			(layer "B.Fab")
		)
		(fp_line
			(start -0.67945 0.3048)
			(end -0.120396 0.3048)
			(stroke
				(width 0.1)
				(type default)
			)
			(layer "B.Fab")
		)
		(fp_line
			(start -0.67945 -0.3048)
			(end -0.67945 0.3048)
			(stroke
				(width 0.1)
				(type default)
			)
			(layer "B.Fab")
		)
		(pad "1" smd circle
			(at 0.40005 0)
			(size 0 0)
			(layers "B.Cu" "B.Mask" "B.Paste")
			(net "P3V3_AUX")
		)
		(pad "2" smd circle
			(at -0.40005 0)
			(size 0 0)
			(layers "B.Cu" "B.Mask" "B.Paste")
			(net "PU_RST_DEDI_BUSY_PLD_N")
		)
	)
)
